# T6G (Grand Teton) — schematic netlist excerpt (pin names and nets, part order shuffled) for the footprints in the layout excerpt that follows; sources: Cadence DE-HDL packaged netlist, KiCad conversion of 04192023_DAF0TMB3IC0_F0TG_MB_C_brd_V02_OCP.brd

R1489  Q_RES  4.7K 5% EMPTY  pkg 0201LF  page 342 : A = P1V8_CPU1_RT_1D ; B = JTAG_TMS_RT_CPU1_P2
R3874  Q_RES  0 5% EMPTY  pkg 0402LF  page 141 : A = P12V_OCP_IMON_2 ; B = P12V_OCP_V3_2_ISENSE_MPS_TIC
PC141_6  Q_CAP  0.1UF 25V 10% X7R  pkg 0402  page 220 : A = SW_P12V_AUX_PVDDCR_CPU1_P1_FLT ; B = GND

(kicad_pcb
	(version 20260206)
	(generator "pcbnew")
	(generator_version "10.0")
	(general
		(thickness 1.6)
		(legacy_teardrops no)
	)
	(paper "A4")
	(title_block
		(title "04192023_DAF0TMB3IC0_F0TG_MB_C_brd_V02_OCP.brd")
		(comment 1 "Grand Teton / footprints 2074-2076 of 8354")
	)
	(layers
		(0 "F.Cu" signal "TOP")
		(4 "In1.Cu" signal "GND")
		(6 "In2.Cu" signal "IN1")
		(8 "In3.Cu" signal "GND1")
		(10 "In4.Cu" signal "IN2")
		(12 "In5.Cu" signal "GND2")
		(14 "In6.Cu" signal "IN3")
		(16 "In7.Cu" signal "GND3")
		(18 "In8.Cu" signal "VCC")
		(20 "In9.Cu" signal "VCC1")
		(22 "In10.Cu" signal "GND4")
		(24 "In11.Cu" signal "IN4")
		(26 "In12.Cu" signal "GND5")
		(28 "In13.Cu" signal "IN5")
		(30 "In14.Cu" signal "GND6")
		(32 "In15.Cu" signal "IN6")
		(34 "In16.Cu" signal "GND7")
		(2 "B.Cu" signal "BOTTOM")
		(9 "F.Adhes" user "F.Adhesive")
		(11 "B.Adhes" user "B.Adhesive")
		(13 "F.Paste" user "Package Geometry/Pastemask Top")
		(15 "B.Paste" user "Package Geometry/Pastemask Bottom")
		(5 "F.SilkS" user "Ref Des/Silkscreen Top")
		(7 "B.SilkS" user "Ref Des/Silkscreen Bottom")
		(1 "F.Mask" user "Board Geometry/Soldermask Top")
		(3 "B.Mask" user "Board Geometry/Soldermask Bottom")
		(17 "Dwgs.User" user "User.Drawings")
		(19 "Cmts.User" user "User.Comments")
		(21 "Eco1.User" user "User.Eco1")
		(23 "Eco2.User" user "User.Eco2")
		(25 "Edge.Cuts" user "Board Geometry/Outline")
		(27 "Margin" user)
		(31 "F.CrtYd" user "Package Geometry/Place Bound Top")
		(29 "B.CrtYd" user "Package Geometry/Place Bound Bottom")
		(35 "F.Fab" user "Ref Des/Assembly Top")
		(33 "B.Fab" user "Ref Des/Assembly Bottom")
	)
	(footprint ""
		(layer "F.Cu")
		(at 108.346494 -340.085426 -90)
		(property "Reference" "PC141_6"
			(at 0 0 270)
			(layer "F.SilkS")
			(hide yes)
			(effects
				(font
					(size 1.27 1.27)
				)
			)
		)
		(property "Value" ""
			(at 0 0 270)
			(layer "F.Fab")
			(effects
				(font
					(size 1.27 1.27)
				)
			)
		)
		(duplicate_pad_numbers_are_jumpers no)
		(fp_line
			(start -0.7874 0.4064)
			(end -0.7874 -0.4064)
			(stroke
				(width 0.1524)
				(type default)
			)
			(layer "F.SilkS")
		)
		(fp_line
			(start 0.7874 0.4064)
			(end -0.7874 0.4064)
			(stroke
				(width 0.1524)
				(type default)
			)
			(layer "F.SilkS")
		)
		(fp_line
			(start -0.7874 -0.4064)
			(end 0.7874 -0.4064)
			(stroke
				(width 0.1524)
				(type default)
			)
			(layer "F.SilkS")
		)
		(fp_line
			(start 0.7874 -0.4064)
			(end 0.7874 0.4064)
			(stroke
				(width 0.1524)
				(type default)
			)
			(layer "F.SilkS")
		)
		(fp_line
			(start -0.67945 0.3048)
			(end -0.67945 -0.305054)
			(stroke
				(width 0.1)
				(type default)
			)
			(layer "F.Fab")
		)
		(fp_line
			(start -0.12065 0.3048)
			(end -0.67945 0.3048)
			(stroke
				(width 0.1)
				(type default)
			)
			(layer "F.Fab")
		)
		(fp_line
			(start 0.120396 0.3048)
			(end 0.120396 0.2794)
			(stroke
				(width 0.1)
				(type default)
			)
			(layer "F.Fab")
		)
		(fp_line
			(start 0.67945 0.3048)
			(end 0.120396 0.3048)
			(stroke
				(width 0.1)
				(type default)
			)
			(layer "F.Fab")
		)
		(fp_line
			(start -0.12065 0.2794)
			(end -0.12065 0.3048)
			(stroke
				(width 0.1)
				(type default)
			)
			(layer "F.Fab")
		)
		(fp_line
			(start 0.120396 0.2794)
			(end -0.12065 0.2794)
			(stroke
				(width 0.1)
				(type default)
			)
			(layer "F.Fab")
		)
		(fp_line
			(start -0.12065 -0.2794)
			(end 0.12065 -0.2794)
			(stroke
				(width 0.1)
				(type default)
			)
			(layer "F.Fab")
		)
		(fp_line
			(start 0.12065 -0.2794)
			(end 0.12065 -0.3048)
			(stroke
				(width 0.1)
				(type default)
			)
			(layer "F.Fab")
		)
		(fp_line
			(start 0.12065 -0.3048)
			(end 0.67945 -0.3048)
			(stroke
				(width 0.1)
				(type default)
			)
			(layer "F.Fab")
		)
		(fp_line
			(start 0.67945 -0.3048)
			(end 0.67945 0.3048)
			(stroke
				(width 0.1)
				(type default)
			)
			(layer "F.Fab")
		)
		(fp_line
			(start -0.67945 -0.305054)
			(end -0.12065 -0.305054)
			(stroke
				(width 0.1)
				(type default)
			)
			(layer "F.Fab")
		)
		(fp_line
			(start -0.12065 -0.305054)
			(end -0.12065 -0.2794)
			(stroke
				(width 0.1)
				(type default)
			)
			(layer "F.Fab")
		)
		(pad "1" smd circle
			(at -0.40005 0 270)
			(size 0 0)
			(layers "F.Cu" "F.Mask" "F.Paste")
			(net "SW_P12V_AUX_PVDDCR_CPU1_P1_FLT")
		)
		(pad "2" smd circle
			(at 0.40005 0 270)
			(size 0 0)
			(layers "F.Cu" "F.Mask" "F.Paste")
			(net "GND")
		)
	)
	(footprint ""
		(layer "F.Cu")
		(at 177.81016 -389.0518)
		(property "Reference" "R1489"
			(at 0 0 0)
			(layer "F.SilkS")
			(hide yes)
			(effects
				(font
					(size 1.27 1.27)
				)
			)
		)
		(property "Value" ""
			(at 0 0 0)
			(layer "F.Fab")
			(effects
				(font
					(size 1.27 1.27)
				)
			)
		)
		(duplicate_pad_numbers_are_jumpers no)
		(fp_line
			(start -0.32512 -0.175006)
			(end 0.32512 -0.175006)
			(stroke
				(width 0.1)
				(type default)
			)
			(layer "F.Fab")
		)
		(fp_line
			(start -0.32512 0.175006)
			(end -0.32512 -0.175006)
			(stroke
				(width 0.1)
				(type default)
			)
			(layer "F.Fab")
		)
		(fp_line
			(start 0.32512 -0.175006)
			(end 0.32512 0.175006)
			(stroke
				(width 0.1)
				(type default)
			)
			(layer "F.Fab")
		)
		(fp_line
			(start 0.32512 0.175006)
			(end -0.32512 0.175006)
			(stroke
				(width 0.1)
				(type default)
			)
			(layer "F.Fab")
		)
		(pad "1" smd rect
			(at -0.2667 0)
			(size 0.3048 0.381)
			(layers "F.Cu" "F.Mask" "F.Paste")
			(net "P1V8_CPU1_RT_1D")
		)
		(pad "2" smd rect
			(at 0.2667 0 180)
			(size 0.3048 0.381)
			(layers "F.Cu" "F.Mask" "F.Paste")
			(net "JTAG_TMS_RT_CPU1_P2")
		)
	)
	(footprint ""
		(layer "F.Cu")
		(at 61.543438 -31.887922 90)
		(property "Reference" "R3874"
			(at 0 0 90)
			(layer "F.SilkS")
			(hide yes)
			(effects
				(font
					(size 1.27 1.27)
				)
			)
		)
		(property "Value" ""
			(at 0 0 90)
			(layer "F.Fab")
			(effects
				(font
					(size 1.27 1.27)
				)
			)
		)
		(duplicate_pad_numbers_are_jumpers no)
		(fp_line
			(start 0.7874 -0.4064)
			(end 0.7874 0.4064)
			(stroke
				(width 0.1524)
				(type default)
			)
			(layer "F.SilkS")
		)
		(fp_line
			(start -0.7874 -0.4064)
			(end 0.7874 -0.4064)
			(stroke
				(width 0.1524)
				(type default)
			)
			(layer "F.SilkS")
		)
		(fp_line
			(start 0.7874 0.4064)
			(end -0.7874 0.4064)
			(stroke
				(width 0.1524)
				(type default)
			)
			(layer "F.SilkS")
		)
		(fp_line
			(start -0.7874 0.4064)
			(end -0.7874 -0.4064)
			(stroke
				(width 0.1524)
				(type default)
			)
			(layer "F.SilkS")
		)
		(fp_line
			(start -0.12065 -0.305054)
			(end -0.12065 -0.2794)
			(stroke
				(width 0.1)
				(type default)
			)
			(layer "F.Fab")
		)
		(fp_line
			(start -0.67945 -0.305054)
			(end -0.12065 -0.305054)
			(stroke
				(width 0.1)
				(type default)
			)
			(layer "F.Fab")
		)
		(fp_line
			(start 0.67945 -0.3048)
			(end 0.67945 0.3048)
			(stroke
				(width 0.1)
				(type default)
			)
			(layer "F.Fab")
		)
		(fp_line
			(start 0.12065 -0.3048)
			(end 0.67945 -0.3048)
			(stroke
				(width 0.1)
				(type default)
			)
			(layer "F.Fab")
		)
		(fp_line
			(start 0.12065 -0.2794)
			(end 0.12065 -0.3048)
			(stroke
				(width 0.1)
				(type default)
			)
			(layer "F.Fab")
		)
		(fp_line
			(start -0.12065 -0.2794)
			(end 0.12065 -0.2794)
			(stroke
				(width 0.1)
				(type default)
			)
			(layer "F.Fab")
		)
		(fp_line
			(start 0.120396 0.2794)
			(end -0.12065 0.2794)
			(stroke
				(width 0.1)
				(type default)
			)
			(layer "F.Fab")
		)
		(fp_line
			(start -0.12065 0.2794)
			(end -0.12065 0.3048)
			(stroke
				(width 0.1)
				(type default)
			)
			(layer "F.Fab")
		)
		(fp_line
			(start 0.67945 0.3048)
			(end 0.120396 0.3048)
			(stroke
				(width 0.1)
				(type default)
			)
			(layer "F.Fab")
		)
		(fp_line
			(start 0.120396 0.3048)
			(end 0.120396 0.2794)
			(stroke
				(width 0.1)
				(type default)
			)
			(layer "F.Fab")
		)
		(fp_line
			(start -0.12065 0.3048)
			(end -0.67945 0.3048)
			(stroke
				(width 0.1)
				(type default)
			)
			(layer "F.Fab")
		)
		(fp_line
			(start -0.67945 0.3048)
			(end -0.67945 -0.305054)
			(stroke
				(width 0.1)
				(type default)
			)
			(layer "F.Fab")
		)
		(pad "1" smd circle
			(at -0.40005 0 90)
			(size 0 0)
			(layers "F.Cu" "F.Mask" "F.Paste")
			(net "P12V_OCP_IMON_2")
		)
		(pad "2" smd circle
			(at 0.40005 0 90)
			(size 0 0)
			(layers "F.Cu" "F.Mask" "F.Paste")
			(net "P12V_OCP_V3_2_ISENSE_MPS_TIC")
		)
	)
)
